(kicad_pcb
	(version 20260206)
	(generator "pcbnew")
	(generator_version "10.0")
	(general
		(thickness 1.6)
		(legacy_teardrops no)
	)
	(paper "A4")
	(title_block
		(title "Wiwynn_Tioga_Pass_MB.brd")
		(comment 1 "Tioga Pass / footprints 335-342 of 4770")
	)
	(layers
		(0 "F.Cu" signal "TOP")
		(4 "In1.Cu" signal "L2GND")
		(6 "In2.Cu" signal "L3")
		(8 "In3.Cu" signal "L4GND")
		(10 "In4.Cu" signal "L5")
		(12 "In5.Cu" signal "L6GND")
		(14 "In6.Cu" signal "L7VCC")
		(16 "In7.Cu" signal "L8VCC")
		(18 "In8.Cu" signal "L9GND")
		(20 "In9.Cu" signal "L10")
		(22 "In10.Cu" signal "L11GND")
		(24 "In11.Cu" signal "L12")
		(26 "In12.Cu" signal "L13GND")
		(2 "B.Cu" signal "BOTTOM")
		(9 "F.Adhes" user "F.Adhesive")
		(11 "B.Adhes" user "B.Adhesive")
		(13 "F.Paste" user "Package Geometry/Pastemask Top")
		(15 "B.Paste" user "Package Geometry/Pastemask Bottom")
		(5 "F.SilkS" user "Ref Des/Silkscreen Top")
		(7 "B.SilkS" user "Ref Des/Silkscreen Bottom")
		(1 "F.Mask" user "Board Geometry/Soldermask Top")
		(3 "B.Mask" user "Board Geometry/Soldermask Bottom")
		(17 "Dwgs.User" user "User.Drawings")
		(19 "Cmts.User" user "User.Comments")
		(21 "Eco1.User" user "User.Eco1")
		(23 "Eco2.User" user "User.Eco2")
		(25 "Edge.Cuts" user "Board Geometry/Outline")
		(27 "Margin" user)
		(31 "F.CrtYd" user "Package Geometry/Place Bound Top")
		(29 "B.CrtYd" user "Package Geometry/Place Bound Bottom")
		(35 "F.Fab" user "Ref Des/Assembly Top")
		(33 "B.Fab" user "Ref Des/Assembly Bottom")
	)
	(footprint ""
		(layer "F.Cu")
		(at 369.57 -136.4615 180)
		(property "Reference" "R7A19"
			(at 0 0 180)
			(layer "F.SilkS")
			(hide yes)
			(effects
				(font
					(size 1.27 1.27)
				)
			)
		)
		(property "Value" ""
			(at 0 0 180)
			(layer "F.Fab")
			(effects
				(font
					(size 1.27 1.27)
				)
			)
		)
		(duplicate_pad_numbers_are_jumpers no)
		(fp_poly
			(pts
				(xy -0.2794 -0.1016) (xy 0.2794 -0.1016) (xy 0.2794 0.9906) (xy -0.2794 0.9906)
			)
			(stroke
				(width 0)
				(type default)
			)
			(fill no)
			(layer "F.CrtYd")
		)
		(fp_line
			(start 0.2794 0.9906)
			(end 0.2794 -0.1016)
			(stroke
				(width 0.1)
				(type default)
			)
			(layer "F.Fab")
		)
		(fp_line
			(start 0.2794 -0.1016)
			(end -0.2794 -0.1016)
			(stroke
				(width 0.1)
				(type default)
			)
			(layer "F.Fab")
		)
		(fp_line
			(start -0.2794 0.9906)
			(end 0.2794 0.9906)
			(stroke
				(width 0.1)
				(type default)
			)
			(layer "F.Fab")
		)
		(fp_line
			(start -0.2794 -0.1016)
			(end -0.2794 0.9906)
			(stroke
				(width 0.1)
				(type default)
			)
			(layer "F.Fab")
		)
		(pad "1" smd rect
			(at 0 0 180)
			(size 0.508 0.508)
			(layers "F.Cu" "F.Mask" "F.Paste")
			(net "VSENSE_PVNN_PCH_STBY_QAT")
		)
		(pad "2" smd rect
			(at 0 0.889 180)
			(size 0.508 0.508)
			(layers "F.Cu" "F.Mask" "F.Paste")
			(net "VSENSE_PVNN_PCH_STBY_AVSP")
		)
		(zone
			(layer "F.Cu")
			(hatch none 0.5)
			(connect_pads
				(clearance 0)
			)
			(min_thickness 0.25)
			(keepout
				(tracks not_allowed)
				(vias allowed)
				(pads allowed)
				(copperpour not_allowed)
				(footprints allowed)
			)
			(placement
				(enabled no)
				(sheetname "")
			)
			(fill
				(thermal_gap 0.5)
				(thermal_bridge_width 0.5)
				(island_removal_mode 0)
			)
			(polygon
				(pts
					(xy 369.824 -137.0965) (xy 369.316 -137.0965) (xy 369.316 -136.7155) (xy 369.824 -136.7155)
				)
			)
		)
		(zone
			(layer "F.Cu")
			(hatch none 0.5)
			(connect_pads
				(clearance 0)
			)
			(min_thickness 0.25)
			(keepout
				(tracks allowed)
				(vias not_allowed)
				(pads allowed)
				(copperpour not_allowed)
				(footprints allowed)
			)
			(placement
				(enabled no)
				(sheetname "")
			)
			(fill
				(thermal_gap 0.5)
				(thermal_bridge_width 0.5)
				(island_removal_mode 0)
			)
			(polygon
				(pts
					(xy 369.824 -136.7155) (xy 369.316 -136.7155) (xy 369.316 -137.0965) (xy 369.824 -137.0965)
				)
			)
		)
	)
	(footprint ""
		(layer "F.Cu")
		(at 80.757268 -12.954 -90)
		(property "Reference" "C2G1"
			(at 1.848866 0.752348 270)
			(unlocked yes)
			(layer "F.SilkS")
			(effects
				(font
					(size 1.27 0.9652)
					(thickness 0.1524)
				)
			)
		)
		(property "Value" ""
			(at 0 0 270)
			(layer "F.Fab")
			(effects
				(font
					(size 1.27 1.27)
				)
			)
		)
		(duplicate_pad_numbers_are_jumpers no)
		(fp_rect
			(start -0.500126 1.598422)
			(end 0.500126 -0.201422)
			(stroke
				(width 0)
				(type default)
			)
			(fill no)
			(layer "F.CrtYd")
		)
		(fp_line
			(start -0.500126 1.598422)
			(end -0.500126 -0.201422)
			(stroke
				(width 0.1)
				(type default)
			)
			(layer "F.Fab")
		)
		(fp_line
			(start 0.500126 1.598422)
			(end -0.500126 1.598422)
			(stroke
				(width 0.1)
				(type default)
			)
			(layer "F.Fab")
		)
		(fp_line
			(start -0.500126 -0.201422)
			(end 0.500126 -0.201422)
			(stroke
				(width 0.1)
				(type default)
			)
			(layer "F.Fab")
		)
		(fp_line
			(start 0.500126 -0.201422)
			(end 0.500126 1.598422)
			(stroke
				(width 0.1)
				(type default)
			)
			(layer "F.Fab")
		)
		(pad "1" smd rect
			(at 0 0 180)
			(size 0.889 0.9906)
			(layers "F.Cu" "F.Mask" "F.Paste")
			(net "PVDDQ_GHJ")
		)
		(pad "2" smd rect
			(at 0 1.397 180)
			(size 0.889 0.9906)
			(layers "F.Cu" "F.Mask" "F.Paste")
			(net "GND")
		)
		(zone
			(layer "F.Cu")
			(hatch none 0.5)
			(connect_pads
				(clearance 0)
			)
			(min_thickness 0.25)
			(keepout
				(tracks allowed)
				(vias not_allowed)
				(pads allowed)
				(copperpour not_allowed)
				(footprints allowed)
			)
			(placement
				(enabled no)
				(sheetname "")
			)
			(fill
				(thermal_gap 0.5)
				(thermal_bridge_width 0.5)
				(island_removal_mode 0)
			)
			(polygon
				(pts
					(xy 79.804768 -13.4493) (xy 79.804768 -12.4587) (xy 80.312768 -12.4587) (xy 80.312768 -13.4493)
				)
			)
		)
		(zone
			(layer "F.Cu")
			(hatch none 0.5)
			(connect_pads
				(clearance 0)
			)
			(min_thickness 0.25)
			(keepout
				(tracks not_allowed)
				(vias allowed)
				(pads allowed)
				(copperpour not_allowed)
				(footprints allowed)
			)
			(placement
				(enabled no)
				(sheetname "")
			)
			(fill
				(thermal_gap 0.5)
				(thermal_bridge_width 0.5)
				(island_removal_mode 0)
			)
			(polygon
				(pts
					(xy 79.804768 -13.4493) (xy 79.804768 -12.4587) (xy 80.312768 -12.4587) (xy 80.312768 -13.4493)
				)
			)
		)
	)
	(footprint ""
		(layer "F.Cu")
		(at 417.703 -83.439 -90)
		(property "Reference" "C8D3"
			(at 0 0 270)
			(layer "F.SilkS")
			(hide yes)
			(effects
				(font
					(size 1.27 1.27)
				)
			)
		)
		(property "Value" ""
			(at 0 0 270)
			(layer "F.Fab")
			(effects
				(font
					(size 1.27 1.27)
				)
			)
		)
		(duplicate_pad_numbers_are_jumpers no)
		(fp_poly
			(pts
				(xy 0.3048 -0.1016) (xy 0.3048 0.9906) (xy -0.3048 0.9906) (xy -0.3048 -0.1016)
			)
			(stroke
				(width 0)
				(type default)
			)
			(fill no)
			(layer "F.CrtYd")
		)
		(fp_line
			(start -0.3048 0.9906)
			(end 0.3048 0.9906)
			(stroke
				(width 0.1)
				(type default)
			)
			(layer "F.Fab")
		)
		(fp_line
			(start 0.3048 0.9906)
			(end 0.3048 -0.1016)
			(stroke
				(width 0.1)
				(type default)
			)
			(layer "F.Fab")
		)
		(fp_line
			(start -0.3048 -0.1016)
			(end -0.3048 0.9906)
			(stroke
				(width 0.1)
				(type default)
			)
			(layer "F.Fab")
		)
		(fp_line
			(start 0.3048 -0.1016)
			(end -0.3048 -0.1016)
			(stroke
				(width 0.1)
				(type default)
			)
			(layer "F.Fab")
		)
		(pad "1" smd rect
			(at 0 0 270)
			(size 0.508 0.508)
			(layers "F.Cu" "F.Mask" "F.Paste")
			(net "IRQ_SML1_PMBUS_ALERT_N")
		)
		(pad "2" smd rect
			(at 0 0.889 270)
			(size 0.508 0.508)
			(layers "F.Cu" "F.Mask" "F.Paste")
			(net "GND")
		)
		(zone
			(layer "F.Cu")
			(hatch none 0.5)
			(connect_pads
				(clearance 0)
			)
			(min_thickness 0.25)
			(keepout
				(tracks not_allowed)
				(vias allowed)
				(pads allowed)
				(copperpour not_allowed)
				(footprints allowed)
			)
			(placement
				(enabled no)
				(sheetname "")
			)
			(fill
				(thermal_gap 0.5)
				(thermal_bridge_width 0.5)
				(island_removal_mode 0)
			)
			(polygon
				(pts
					(xy 417.068 -83.693) (xy 417.068 -83.185) (xy 417.449 -83.185) (xy 417.449 -83.693)
				)
			)
		)
		(zone
			(layer "F.Cu")
			(hatch none 0.5)
			(connect_pads
				(clearance 0)
			)
			(min_thickness 0.25)
			(keepout
				(tracks allowed)
				(vias not_allowed)
				(pads allowed)
				(copperpour not_allowed)
				(footprints allowed)
			)
			(placement
				(enabled no)
				(sheetname "")
			)
			(fill
				(thermal_gap 0.5)
				(thermal_bridge_width 0.5)
				(island_removal_mode 0)
			)
			(polygon
				(pts
					(xy 417.449 -83.693) (xy 417.449 -83.185) (xy 417.068 -83.185) (xy 417.068 -83.693)
				)
			)
		)
	)
	(footprint ""
		(layer "F.Cu")
		(at 205.036928 -57.031382)
		(property "Reference" "L4E1"
			(at 3.378708 -4.251706 0)
			(unlocked yes)
			(layer "F.SilkS")
			(effects
				(font
					(size 0.4064 0.254)
					(thickness 0.1524)
				)
			)
		)
		(property "Value" ""
			(at 0 0 0)
			(layer "F.Fab")
			(effects
				(font
					(size 1.27 1.27)
				)
			)
		)
		(duplicate_pad_numbers_are_jumpers no)
		(fp_line
			(start -1.1303 -3.199892)
			(end 8.3693 -3.199892)
			(stroke
				(width 0.1524)
				(type default)
			)
			(layer "F.SilkS")
		)
		(fp_line
			(start -1.1303 -1.6637)
			(end -1.1303 -3.199892)
			(stroke
				(width 0.1524)
				(type default)
			)
			(layer "F.SilkS")
		)
		(fp_line
			(start -1.1303 3.199892)
			(end -1.1303 1.6637)
			(stroke
				(width 0.1524)
				(type default)
			)
			(layer "F.SilkS")
		)
		(fp_line
			(start 8.3693 -3.199892)
			(end 8.3693 -1.6637)
			(stroke
				(width 0.1524)
				(type default)
			)
			(layer "F.SilkS")
		)
		(fp_line
			(start 8.3693 1.6637)
			(end 8.3693 3.199892)
			(stroke
				(width 0.1524)
				(type default)
			)
			(layer "F.SilkS")
		)
		(fp_line
			(start 8.3693 3.199892)
			(end -1.1303 3.199892)
			(stroke
				(width 0.1524)
				(type default)
			)
			(layer "F.SilkS")
		)
		(fp_rect
			(start -1.1303 3.199892)
			(end 8.3693 -3.199892)
			(stroke
				(width 0)
				(type default)
			)
			(fill no)
			(layer "F.CrtYd")
		)
		(fp_line
			(start -1.1303 -3.199892)
			(end 8.3693 -3.199892)
			(stroke
				(width 0.1)
				(type default)
			)
			(layer "F.Fab")
		)
		(fp_line
			(start -1.1303 3.199892)
			(end -1.1303 -3.199892)
			(stroke
				(width 0.1)
				(type default)
			)
			(layer "F.Fab")
		)
		(fp_line
			(start 8.3693 -3.199892)
			(end 8.3693 3.199892)
			(stroke
				(width 0.1)
				(type default)
			)
			(layer "F.Fab")
		)
		(fp_line
			(start 8.3693 3.199892)
			(end -1.1303 3.199892)
			(stroke
				(width 0.1)
				(type default)
			)
			(layer "F.Fab")
		)
		(pad "1" smd rect
			(at 0 0)
			(size 3.683 2.667)
			(layers "F.Cu" "F.Mask" "F.Paste")
			(net "VR_PVCCIN_CPU0_PHASE1")
		)
		(pad "2" smd rect
			(at 7.239 0)
			(size 3.683 2.667)
			(layers "F.Cu" "F.Mask" "F.Paste")
			(net "PVCCIN_CPU0")
		)
	)
	(footprint ""
		(layer "F.Cu")
		(at 355.149404 -137.150348 180)
		(property "Reference" "C12W2"
			(at -0.8382 -0.67818 180)
			(unlocked yes)
			(layer "F.SilkS")
			(effects
				(font
					(size 0.4064 0.254)
					(thickness 0.1524)
				)
				(justify left)
			)
		)
		(property "Value" ""
			(at 0 0 180)
			(layer "F.Fab")
			(effects
				(font
					(size 1.27 1.27)
				)
			)
		)
		(duplicate_pad_numbers_are_jumpers no)
		(fp_poly
			(pts
				(xy 0.3048 -0.1016) (xy 0.3048 0.9906) (xy -0.3048 0.9906) (xy -0.3048 -0.1016)
			)
			(stroke
				(width 0)
				(type default)
			)
			(fill no)
			(layer "F.CrtYd")
		)
		(fp_line
			(start 0.3048 0.9906)
			(end 0.3048 -0.1016)
			(stroke
				(width 0.1)
				(type default)
			)
			(layer "F.Fab")
		)
		(fp_line
			(start 0.3048 -0.1016)
			(end -0.3048 -0.1016)
			(stroke
				(width 0.1)
				(type default)
			)
			(layer "F.Fab")
		)
		(fp_line
			(start -0.3048 0.9906)
			(end 0.3048 0.9906)
			(stroke
				(width 0.1)
				(type default)
			)
			(layer "F.Fab")
		)
		(fp_line
			(start -0.3048 -0.1016)
			(end -0.3048 0.9906)
			(stroke
				(width 0.1)
				(type default)
			)
			(layer "F.Fab")
		)
		(pad "1" smd rect
			(at 0 0 180)
			(size 0.508 0.508)
			(layers "F.Cu" "F.Mask" "F.Paste")
			(net "VR_PVDDQ_DEF_AIINSEN")
		)
		(pad "2" smd rect
			(at 0 0.889 180)
			(size 0.508 0.508)
			(layers "F.Cu" "F.Mask" "F.Paste")
			(net "VR_PVDDQ_DEF_VINSEN")
		)
		(zone
			(layer "F.Cu")
			(hatch none 0.5)
			(connect_pads
				(clearance 0)
			)
			(min_thickness 0.25)
			(keepout
				(tracks not_allowed)
				(vias allowed)
				(pads allowed)
				(copperpour not_allowed)
				(footprints allowed)
			)
			(placement
				(enabled no)
				(sheetname "")
			)
			(fill
				(thermal_gap 0.5)
				(thermal_bridge_width 0.5)
				(island_removal_mode 0)
			)
			(polygon
				(pts
					(xy 355.403404 -137.785348) (xy 354.895404 -137.785348) (xy 354.895404 -137.404348) (xy 355.403404 -137.404348)
				)
			)
		)
		(zone
			(layer "F.Cu")
			(hatch none 0.5)
			(connect_pads
				(clearance 0)
			)
			(min_thickness 0.25)
			(keepout
				(tracks allowed)
				(vias not_allowed)
				(pads allowed)
				(copperpour not_allowed)
				(footprints allowed)
			)
			(placement
				(enabled no)
				(sheetname "")
			)
			(fill
				(thermal_gap 0.5)
				(thermal_bridge_width 0.5)
				(island_removal_mode 0)
			)
			(polygon
				(pts
					(xy 355.403404 -137.404348) (xy 354.895404 -137.404348) (xy 354.895404 -137.785348) (xy 355.403404 -137.785348)
				)
			)
		)
	)
	(footprint ""
		(layer "F.Cu")
		(at 383.14757 -78.140814 90)
		(property "Reference" "R7D27"
			(at 0 0 90)
			(layer "F.SilkS")
			(hide yes)
			(effects
				(font
					(size 1.27 1.27)
				)
			)
		)
		(property "Value" ""
			(at 0 0 90)
			(layer "F.Fab")
			(effects
				(font
					(size 1.27 1.27)
				)
			)
		)
		(duplicate_pad_numbers_are_jumpers no)
		(fp_poly
			(pts
				(xy -0.2794 -0.1016) (xy 0.2794 -0.1016) (xy 0.2794 0.9906) (xy -0.2794 0.9906)
			)
			(stroke
				(width 0)
				(type default)
			)
			(fill no)
			(layer "F.CrtYd")
		)
		(fp_line
			(start 0.2794 -0.1016)
			(end -0.2794 -0.1016)
			(stroke
				(width 0.1)
				(type default)
			)
			(layer "F.Fab")
		)
		(fp_line
			(start -0.2794 -0.1016)
			(end -0.2794 0.9906)
			(stroke
				(width 0.1)
				(type default)
			)
			(layer "F.Fab")
		)
		(fp_line
			(start 0.2794 0.9906)
			(end 0.2794 -0.1016)
			(stroke
				(width 0.1)
				(type default)
			)
			(layer "F.Fab")
		)
		(fp_line
			(start -0.2794 0.9906)
			(end 0.2794 0.9906)
			(stroke
				(width 0.1)
				(type default)
			)
			(layer "F.Fab")
		)
		(pad "1" smd rect
			(at 0 0 90)
			(size 0.508 0.508)
			(layers "F.Cu" "F.Mask" "F.Paste")
			(net "H_CPU0_MSMI_G_N")
		)
		(pad "2" smd rect
			(at 0 0.889 90)
			(size 0.508 0.508)
			(layers "F.Cu" "F.Mask" "F.Paste")
			(net "H_CPU_MSMI_G_N")
		)
		(zone
			(layer "F.Cu")
			(hatch none 0.5)
			(connect_pads
				(clearance 0)
			)
			(min_thickness 0.25)
			(keepout
				(tracks allowed)
				(vias not_allowed)
				(pads allowed)
				(copperpour not_allowed)
				(footprints allowed)
			)
			(placement
				(enabled no)
				(sheetname "")
			)
			(fill
				(thermal_gap 0.5)
				(thermal_bridge_width 0.5)
				(island_removal_mode 0)
			)
			(polygon
				(pts
					(xy 383.40157 -77.886814) (xy 383.40157 -78.394814) (xy 383.78257 -78.394814) (xy 383.78257 -77.886814)
				)
			)
		)
		(zone
			(layer "F.Cu")
			(hatch none 0.5)
			(connect_pads
				(clearance 0)
			)
			(min_thickness 0.25)
			(keepout
				(tracks not_allowed)
				(vias allowed)
				(pads allowed)
				(copperpour not_allowed)
				(footprints allowed)
			)
			(placement
				(enabled no)
				(sheetname "")
			)
			(fill
				(thermal_gap 0.5)
				(thermal_bridge_width 0.5)
				(island_removal_mode 0)
			)
			(polygon
				(pts
					(xy 383.78257 -77.886814) (xy 383.78257 -78.394814) (xy 383.40157 -78.394814) (xy 383.40157 -77.886814)
				)
			)
		)
	)
	(footprint ""
		(layer "F.Cu")
		(at 490.35081 -155.293314 -90)
		(property "Reference" "C9A1"
			(at 0 0 270)
			(layer "F.SilkS")
			(hide yes)
			(effects
				(font
					(size 1.27 1.27)
				)
			)
		)
		(property "Value" ""
			(at 0 0 270)
			(layer "F.Fab")
			(effects
				(font
					(size 1.27 1.27)
				)
			)
		)
		(duplicate_pad_numbers_are_jumpers no)
		(fp_poly
			(pts
				(xy 0.3048 -0.1016) (xy 0.3048 0.9906) (xy -0.3048 0.9906) (xy -0.3048 -0.1016)
			)
			(stroke
				(width 0)
				(type default)
			)
			(fill no)
			(layer "F.CrtYd")
		)
		(fp_line
			(start -0.3048 0.9906)
			(end 0.3048 0.9906)
			(stroke
				(width 0.1)
				(type default)
			)
			(layer "F.Fab")
		)
		(fp_line
			(start 0.3048 0.9906)
			(end 0.3048 -0.1016)
			(stroke
				(width 0.1)
				(type default)
			)
			(layer "F.Fab")
		)
		(fp_line
			(start -0.3048 -0.1016)
			(end -0.3048 0.9906)
			(stroke
				(width 0.1)
				(type default)
			)
			(layer "F.Fab")
		)
		(fp_line
			(start 0.3048 -0.1016)
			(end -0.3048 -0.1016)
			(stroke
				(width 0.1)
				(type default)
			)
			(layer "F.Fab")
		)
		(pad "1" smd rect
			(at 0 0 270)
			(size 0.508 0.508)
			(layers "F.Cu" "F.Mask" "F.Paste")
			(net "P5V_STBY_DGB_FS")
		)
		(pad "2" smd rect
			(at 0 0.889 270)
			(size 0.508 0.508)
			(layers "F.Cu" "F.Mask" "F.Paste")
			(net "GND")
		)
		(zone
			(layer "F.Cu")
			(hatch none 0.5)
			(connect_pads
				(clearance 0)
			)
			(min_thickness 0.25)
			(keepout
				(tracks not_allowed)
				(vias allowed)
				(pads allowed)
				(copperpour not_allowed)
				(footprints allowed)
			)
			(placement
				(enabled no)
				(sheetname "")
			)
			(fill
				(thermal_gap 0.5)
				(thermal_bridge_width 0.5)
				(island_removal_mode 0)
			)
			(polygon
				(pts
					(xy 489.71581 -155.547314) (xy 489.71581 -155.039314) (xy 490.09681 -155.039314) (xy 490.09681 -155.547314)
				)
			)
		)
		(zone
			(layer "F.Cu")
			(hatch none 0.5)
			(connect_pads
				(clearance 0)
			)
			(min_thickness 0.25)
			(keepout
				(tracks allowed)
				(vias not_allowed)
				(pads allowed)
				(copperpour not_allowed)
				(footprints allowed)
			)
			(placement
				(enabled no)
				(sheetname "")
			)
			(fill
				(thermal_gap 0.5)
				(thermal_bridge_width 0.5)
				(island_removal_mode 0)
			)
			(polygon
				(pts
					(xy 490.09681 -155.547314) (xy 490.09681 -155.039314) (xy 489.71581 -155.039314) (xy 489.71581 -155.547314)
				)
			)
		)
	)
	(footprint ""
		(layer "F.Cu")
		(at 258.208272 -77.636116)
		(property "Reference" "C5D24"
			(at 0 0 0)
			(layer "F.SilkS")
			(hide yes)
			(effects
				(font
					(size 1.27 1.27)
				)
			)
		)
		(property "Value" ""
			(at 0 0 0)
			(layer "F.Fab")
			(effects
				(font
					(size 1.27 1.27)
				)
			)
		)
		(duplicate_pad_numbers_are_jumpers no)
		(fp_poly
			(pts
				(xy -0.4953 -0.2032) (xy 0.4953 -0.2032) (xy 0.4953 1.6002) (xy -0.4953 1.6002)
			)
			(stroke
				(width 0)
				(type default)
			)
			(fill no)
			(layer "F.CrtYd")
		)
		(fp_line
			(start -0.4953 -0.2032)
			(end 0.4953 -0.2032)
			(stroke
				(width 0.1)
				(type default)
			)
			(layer "F.Fab")
		)
		(fp_line
			(start -0.4953 1.6002)
			(end -0.4953 -0.2032)
			(stroke
				(width 0.1)
				(type default)
			)
			(layer "F.Fab")
		)
		(fp_line
			(start 0.4953 -0.2032)
			(end 0.4953 1.6002)
			(stroke
				(width 0.1)
				(type default)
			)
			(layer "F.Fab")
		)
		(fp_line
			(start 0.4953 1.6002)
			(end -0.4953 1.6002)
			(stroke
				(width 0.1)
				(type default)
			)
			(layer "F.Fab")
		)
		(pad "1" smd rect
			(at 0 0)
			(size 0.762 0.889)
			(layers "F.Cu" "F.Mask" "F.Paste")
			(net "PVCCIN_CPU0")
		)
		(pad "2" smd rect
			(at 0 1.397)
			(size 0.762 0.889)
			(layers "F.Cu" "F.Mask" "F.Paste")
			(net "GND")
		)
		(zone
			(layer "F.Cu")
			(hatch none 0.5)
			(connect_pads
				(clearance 0)
			)
			(min_thickness 0.25)
			(keepout
				(tracks not_allowed)
				(vias allowed)
				(pads allowed)
				(copperpour not_allowed)
				(footprints allowed)
			)
			(placement
				(enabled no)
				(sheetname "")
			)
			(fill
				(thermal_gap 0.5)
				(thermal_bridge_width 0.5)
				(island_removal_mode 0)
			)
			(polygon
				(pts
					(xy 257.827272 -77.191616) (xy 258.589272 -77.191616) (xy 258.589272 -76.683616) (xy 257.827272 -76.683616)
				)
			)
		)
	)
)
